FILE_TYPE = CONNECTIVITY;
{Allegro Design Entry HDL 17.2-2016 S081 (4005846) 1/11/2022}
"PAGE_NUMBER" = 216;
0"NC";
1"P3V3_OCP_V3_2\g";
2"P3V3_OCP_V3_2\g";
3"P3V3_OCP_SFF\g";
4"P3V3_OCP_SFF\g";
5"P3V3_AUX\g";
6"P3V3_AUX\g";
7"GND\g";
8"GND\g";
9"GND\g";
10"GND\g";
11"GND\g";
12"GND\g";
13"SMB_OCP_SFF_3V3AUX_SDA"CDS_PHYS_NET_NAME"SMB_E1S_0_3V3AUX_SDA";
14"SMB_OCP_SFF_3V3AUX_SCL"CDS_PHYS_NET_NAME"SMB_E1S_0_3V3AUX_SCL";
15"SMB_OCP_V3_2_3V3AUX_BUF_SCL"CDS_PHYS_NET_NAME"SMB_E1S_1_3V3AUX_BUF_SCL";
16"SMB_OCP_V3_2_3V3AUX_BUF_SDA"CDS_PHYS_NET_NAME"SMB_E1S_1_3V3AUX_BUF_SDA";
17"HP_LVC3_OCP_V3_2_R_EN"$PHYS_NET_NAME"RST_PCIE_M2_N"CDS_PHYS_NET_NAME"FM_E1S_1_SMB_EN";
18"HP_LVC3_OCP_V3_1_EN"$PHYS_NET_NAME"RST_PCIE_M2_N"CDS_PHYS_NET_NAME"E1S_0_EN";
19"SMB_OCP_SFF_3V3AUX_BUF_SCL"CDS_PHYS_NET_NAME"SMB_E1S_0_3V3AUX_BUF_SCL";
20"SMB_OCP_SFF_3V3AUX_BUF_SDA"CDS_PHYS_NET_NAME"SMB_E1S_0_3V3AUX_BUF_SDA";
21"HP_LVC3_OCP_V3_1_R_EN"$PHYS_NET_NAME"RST_PCIE_M2_N"CDS_PHYS_NET_NAME"FM_E1S_0_SMB_EN";
22"SMB_OCP_V3_2_3V3AUX_SDA"CDS_PHYS_NET_NAME"SMB_E1S_1_3V3AUX_SDA";
23"HP_LVC3_OCP_V3_2_EN"$PHYS_NET_NAME"RST_PCIE_M2_N"CDS_PHYS_NET_NAME"E1S_1_EN";
24"SMB_OCP_V3_2_3V3AUX_SCL"CDS_PHYS_NET_NAME"SMB_E1S_1_3V3AUX_SCL";
%"Q_CAP"
"1","(-8075,3900)","0","pure_quanta","I10";
;
PART_NUMBER"CH4104K1B00"
TOLERANCE"10%"
PACK_TYPE"0402"
MATERIAL"X7R"
VOLTAGE"25V"
VALUE"0.1UF"
$LOCATION"C1859"
CDS_LIB"pure_quanta"
CDS_LOCATION"C1859"
$SEC"1"
CDS_SEC"1";
"B"
$PN"2"7;
"A"
$PN"1"6;
%"Q_CAP"
"1","(-6400,3900)","0","pure_quanta","I11";
;
PART_NUMBER"CH4104K1B00"
VOLTAGE"25V"
PACK_TYPE"0402"
VALUE"0.1UF"
TOLERANCE"10%"
MATERIAL"X7R"
$LOCATION"C1861"
CDS_LIB"pure_quanta"
CDS_LOCATION"C1861"
$SEC"1"
CDS_SEC"1";
"B"
$PN"2"9;
"A"
$PN"1"1;
%"UNIVERSAL_POWER"
"1","(-7725,4200)","0","logical_power","I14";
;
HDL_POWER"P3V3_AUX"
CDS_LIB"logical_power";
"A"6;
%"UNIVERSAL_GND"
"1","(-7650,4850)","0","logical_power","I15";
;
HDL_POWER"GND"
CDS_LIB"logical_power";
"A"10;
%"UNIVERSAL_GND"
"1","(-8050,5500)","0","logical_power","I16";
;
HDL_POWER"GND"
CDS_LIB"logical_power";
"A"11;
%"Q_CAP"
"1","(-8050,5725)","0","pure_quanta","I17";
;
PART_NUMBER"CH4104K1B00"
PACK_TYPE"0402"
VOLTAGE"25V"
MATERIAL"X7R"
TOLERANCE"10%"
VALUE"0.1UF"
$LOCATION"C1860"
CDS_LIB"pure_quanta"
CDS_LOCATION"C1860"
$SEC"1"
CDS_SEC"1";
"B"
$PN"2"11;
"A"
$PN"1"5;
%"UNIVERSAL_POWER"
"1","(-7700,6025)","0","logical_power","I18";
;
HDL_POWER"P3V3_AUX"
CDS_LIB"logical_power";
"A"5;
%"UNIVERSAL_POWER"
"1","(-6600,4200)","0","logical_power","I19";
;
HDL_POWER"P3V3_OCP_V3_2"
CDS_LIB"logical_power";
"A"1;
%"UNIVERSAL_POWER"
"1","(-6575,6025)","0","logical_power","I20";
;
HDL_POWER"P3V3_OCP_SFF"
CDS_LIB"logical_power";
"A"4;
%"Q_RES"
"1","(-5825,5075)","0","pure_quanta","I21";
;
PART_NUMBER"CS00002JB13"
PACK_TYPE"0402LF"
WATTAGE"1/16W"
TOLERANCE"5%"
VALUE"0"
MATERIAL"CHIP"
$LOCATION"R3263"
CDS_LIB"pure_quanta"
CDS_LOCATION"R3263"
$SEC"1"
CDS_SEC"1";
"B"
$PN"2"18;
"A"
$PN"1"21;
%"Q_CAP"
"1","(-6375,5725)","0","pure_quanta","I23";
;
PART_NUMBER"CH4104K1B00"
MATERIAL"X7R"
PACK_TYPE"0402"
VOLTAGE"25V"
VALUE"0.1UF"
TOLERANCE"10%"
$LOCATION"C1862"
CDS_LIB"pure_quanta"
CDS_LOCATION"C1862"
$SEC"1"
CDS_SEC"1";
"B"
$PN"2"12;
"A"
$PN"1"4;
%"UNIVERSAL_GND"
"1","(-6375,5525)","0","logical_power","I24";
;
CDS_LIB"logical_power"
HDL_POWER"GND";
"A"12;
%"PCA9617ADP"
"1","(-7125,5275)","0","pure_quanta","I28";
;
PART_NUMBER"AL009617K02"
MATERIAL"IC"
VALUE"PCA9617ADP"
PART_TYPE"SMLF"
$LOCATION"U236"
CDS_LIB"pure_quanta"
CDS_LMAN_SYM_OUTLINE"-275,300,275,-300"
NEEDS_NO_SIZE"TRUE"
CDS_LOCATION"U236"
$SEC"1"
CDS_SEC"1";
"GND"
$PN"4"10;
"SCLB"
$PN"7"19;
"SDAB"
$PN"6"20;
"SDAA"
$PN"3"13;
"SCLA"
$PN"2"14;
"VCCB"
$PN"8"4;
"VCCA"
$PN"1"5;
"EN"
$PN"5"21;
%"UNIVERSAL_POWER"
"1","(-5400,6000)","0","logical_power","I29";
;
HDL_POWER"P3V3_OCP_SFF"
CDS_LIB"logical_power";
"A"3;
%"UNIVERSAL_GND"
"1","(-8075,3675)","0","logical_power","I3";
;
CDS_LIB"logical_power"
HDL_POWER"GND";
"A"7;
%"Q_RES"
"2","(-5150,5675)","0","pure_quanta","I30";
;
PART_NUMBER"CS24702JB10"
VALUE"4.7K"
TOLERANCE"5%"
WATTAGE"1/16W"
PACK_TYPE"0402LF"
MATERIAL"CHIP"
$LOCATION"R3501"
CDS_LIB"pure_quanta"
CDS_LOCATION"R3501"
$SEC"1"
CDS_SEC"1";
"A"
$PN"1"3;
"B"
$PN"2"20;
%"Q_RES"
"2","(-5400,5675)","0","pure_quanta","I31";
;
PART_NUMBER"CS24702JB10"
WATTAGE"1/16W"
TOLERANCE"5%"
VALUE"4.7K"
PACK_TYPE"0402LF"
MATERIAL"CHIP"
$LOCATION"R3500"
CDS_LIB"pure_quanta"
CDS_LOCATION"R3500"
$SEC"1"
CDS_SEC"1";
"A"
$PN"1"3;
"B"
$PN"2"19;
%"UNIVERSAL_POWER"
"1","(-5575,4175)","0","logical_power","I32";
;
HDL_POWER"P3V3_OCP_V3_2"
CDS_LIB"logical_power";
"A"2;
%"Q_RES"
"2","(-5325,3850)","0","pure_quanta","I33";
;
PART_NUMBER"CS24702JB10"
MATERIAL"CHIP"
PACK_TYPE"0402LF"
TOLERANCE"5%"
VALUE"4.7K"
WATTAGE"1/16W"
$LOCATION"R3520"
CDS_LIB"pure_quanta"
CDS_LOCATION"R3520"
$SEC"1"
CDS_SEC"1";
"A"
$PN"1"2;
"B"
$PN"2"16;
%"Q_RES"
"2","(-5575,3850)","0","pure_quanta","I34";
;
PART_NUMBER"CS24702JB10"
PACK_TYPE"0402LF"
TOLERANCE"5%"
VALUE"4.7K"
WATTAGE"1/16W"
MATERIAL"CHIP"
$LOCATION"R3519"
CDS_LIB"pure_quanta"
CDS_LOCATION"R3519"
$SEC"1"
CDS_SEC"1";
"A"
$PN"1"2;
"B"
$PN"2"15;
%"UNIVERSAL_GND"
"1","(-7675,3025)","0","logical_power","I4";
;
CDS_LIB"logical_power"
HDL_POWER"GND";
"A"8;
%"PCA9617ADP"
"1","(-7150,3450)","0","pure_quanta","I5";
;
PART_NUMBER"AL009617K02"
PART_TYPE"SMLF"
MATERIAL"IC"
VALUE"PCA9617ADP"
$LOCATION"U235"
NEEDS_NO_SIZE"TRUE"
CDS_LMAN_SYM_OUTLINE"-275,300,275,-300"
CDS_LIB"pure_quanta"
CDS_LOCATION"U235"
$SEC"1"
CDS_SEC"1";
"GND"
$PN"4"8;
"SCLB"
$PN"7"15;
"SDAB"
$PN"6"16;
"SDAA"
$PN"3"22;
"SCLA"
$PN"2"24;
"VCCB"
$PN"8"1;
"VCCA"
$PN"1"6;
"EN"
$PN"5"17;
%"UNIVERSAL_GND"
"1","(-6400,3700)","0","logical_power","I6";
;
HDL_POWER"GND"
CDS_LIB"logical_power";
"A"9;
%"Q_RES"
"1","(-5750,3250)","0","pure_quanta","I7";
;
PART_NUMBER"CS00002JB13"
MATERIAL"CHIP"
WATTAGE"1/16W"
TOLERANCE"5%"
PACK_TYPE"0402LF"
VALUE"0"
$LOCATION"R3264"
CDS_LIB"pure_quanta"
CDS_LOCATION"R3264"
$SEC"1"
CDS_SEC"1";
"B"
$PN"2"23;
"A"
$PN"1"17;
END.
